#ISCELL
  mstr_misc dns *
  *
#ISCELL
  mstr_symbols cad_note *
  *
#ISCELL
  mstr_symbols intel_corp_bpage *
  *
#ISCELL
  mstr_standard offpage *
  page161_i100
#CELL
  mstr_discrete res *
  page161_i102
#ISCELL
  mstr_standard offpage *
  page161_i103
#ISCELL
  mstr_symbols gnd *
  page161_i104
#ISCELL
  mstr_symbols p3v3_stby *
  page161_i105
#ISCELL
  mstr_symbols p12v_fan *
  page161_i108
#ISCELL
  mstr_symbols p12v_fan *
  page161_i110
#ISCELL
  mstr_symbols gnd *
  page161_i111
#CELL
  dev_discrete cap_a *
  page161_i113
#ISCELL
  mstr_standard offpage *
  page161_i114
#ISCELL
  mstr_standard offpage *
  page161_i115
#ISCELL
  mstr_standard offpage *
  page161_i116
#ISCELL
  mstr_symbols p3v3_stby *
  page161_i117
#ISCELL
  mstr_symbols gnd *
  page161_i118
#ISCELL
  mstr_symbols p3v3_stby *
  page161_i119
#CELL
  mstr_discrete res *
  page161_i120
#CELL
  mstr_ttl ttl1g08 *
  page161_i121
#ISCELL
  mstr_symbols gnd *
  page161_i122
#ISCELL
  mstr_symbols gnd *
  page161_i13
#CELL
  w_hdl lotes-con4-s1-gp *
  page161_i139
#CELL
  w_hdl lotes-con4-s1-gp *
  page161_i140
#CELL
  dev_discrete cap_a *
  page161_i26
#CELL
  mstr_discrete cap *
  page161_i27
#CELL
  mstr_discrete cap *
  page161_i3
#ISCELL
  mstr_symbols gnd *
  page161_i30
#CELL
  dev_discrete cap_a *
  page161_i4
#CELL
  mstr_discrete diode *
  page161_i42
#CELL
  mstr_discrete res *
  page161_i43
#CELL
  mstr_discrete res *
  page161_i45
#CELL
  dev_discrete cap_a *
  page161_i46
#ISCELL
  mstr_symbols gnd *
  page161_i47
#ISCELL
  mstr_symbols p3v3_stby *
  page161_i48
#ISCELL
  mstr_standard offpage *
  page161_i49
#CELL
  mstr_discrete diode *
  page161_i50
#CELL
  mstr_discrete res *
  page161_i51
#ISCELL
  mstr_symbols p5v_stby *
  page161_i52
#ISCELL
  mstr_standard offpage *
  page161_i53
#ISCELL
  mstr_symbols p3v3_stby *
  page161_i61
#CELL
  mstr_discrete diode *
  page161_i62
#ISCELL
  mstr_symbols p5v_stby *
  page161_i63
#CELL
  mstr_discrete diode *
  page161_i64
#CELL
  mstr_discrete res *
  page161_i65
#CELL
  mstr_discrete res *
  page161_i67
#CELL
  dev_discrete cap_a *
  page161_i68
#ISCELL
  mstr_symbols gnd *
  page161_i69
#CELL
  mstr_discrete res *
  page161_i70
#ISCELL
  mstr_standard offpage *
  page161_i75
#ISCELL
  mstr_standard offpage *
  page161_i76
#CELL
  mstr_ttl ttl1g07_a *
  page161_i88
#CELL
  dev_discrete cap_a *
  page161_i90
#CELL
  mstr_ttl ttl1g07_a *
  page161_i92
#CELL
  dev_discrete cap_a *
  page161_i93
#ISCELL
  mstr_standard offpage *
  page161_i94
#ISCELL
  mstr_symbols p3v3_stby *
  page161_i96
#ISCELL
  mstr_symbols gnd *
  page161_i97
#ISCELL
  mstr_standard offpage *
  page161_i98
#CELL
  mstr_discrete res *
  page161_i99
